FILE_TYPE = CONNECTIVITY;
{Allegro Design Entry HDL 16.6-p007 (v16-6-112F) 10/10/2012}
"PAGE_NUMBER" = 175;
0"NC";
1"GND\g";
2"GND\g";
3"P3V3_STBY\g";
4"GND\g";
5"GND\g";
6"GND\g";
7"GND\g";
8"P3V3_STBY\g";
9"P3V3_STBY\g";
10"GND\g";
11"P5V_STBY\g";
12"P3V3_STBY\g";
13"GND\g";
14"P3V3_STBY\g";
15"GND\g";
16"P3V3_STBY\g";
17"P5V_STBY\g";
18"FM_BEEP_LED_P";
19"RST_SYSTEM_BTN_BUF_N";
20"RST_SYSTEM_BTN_N";
21"FP_ID_LED_XOR_R";
22"FP_PWR_BTN_R_N";
23"FM_DEBUG_RST_BTN_N";
24"FP_PWR_ID_LED_N";
25"FM_BIOS_TOP_SWAP_SPKR";
26"FM_SPEAKER_PCH_N";
27"PWRGD_P3V3";
28"FP_RST_BTN_BUF1_N";
29"FP_RST_BTN_R_N";
30"FP_PWR_BTN_R1_N";
31"FP_PWR_BTN_BUF1_N";
32"PWRGD_P3V3_R";
33"FP_ID_LED_P5V_STBY_N";
34"FM_PWR_BTN_R_N";
35"FM_PWR_BTN_N";
36"FM_SPEAKER_PCH_N_R";
%"TTL2G14"
"1","(-3725,4175)","0","mstr_ttl","I10";
;
CDS_SEC"2"
CDS_LIB"mstr_ttl"
ROOM"MIO_CHASSIS"
CDS_LOCATION"U9A4"
SEC"2"
BOM_COST"MIO_CHASSIS"
SEC_TYPE"SMLF"
PACK_TYPE"SMLF"
PART_NUMBER"D18476-001"
POWER_GROUP"VCC=P3V3_STBY;GND=GND"
MATERIAL"IC"
LOCATION"U9A4"
VALUE"74LVC2G14";
"A <SIZE-1..0>"
$PN"3"31;
"Y <SIZE -1..0> \B"
$PN"4"34;
%"CAP_A"
"1","(-4975,3950)","0","dev_discrete","I11";
;
CDS_LIB"dev_discrete"
CDS_LOCATION"C1L18"
ROOM"MIO_CHASSIS"
SEC"1"
SEC_TYPE"0402V"
CDS_SEC"1"
BOM_COST"MIO_CHASSIS"
MATERIAL"X6S"
VOLTAGE"6.3V"
PACK_TYPE"0402V"
TOLERANCE"10%"
VALUE"1.0UF"
PART_NUMBER"D97712-004"
LOCATION"C1L18";
"B"
$PN"2"1;
"A"
$PN"1"30;
%"GND"
"1","(-4975,3675)","0","mstr_symbols","I12";
;
SIZE"1B"
CDS_LIB"mstr_symbols"
VOLTAGE"0.0V"
BODY_TYPE"PLUMBING"
HDL_POWER"GND";
"A\NAC"1;
%"RES"
"1","(-2750,4175)","0","mstr_discrete","I13";
;
CDS_SEC"1"
CDS_LIB"mstr_discrete"
CDS_LOCATION"R1L26"
SEC"1"
ROOM"MIO_CHASSIS"
BOM_COST"MIO_CHASSIS"
SEC_TYPE"0402"
WATTAGE"1/16W"
MATERIAL"CHIP"
PACK_TYPE"0402"
TOLERANCE"1%"
VALUE"33.2"
LOCATION"R1L26"
PART_NUMBER"G21796-074";
"B"
$PN"2"35;
"A"
$PN"1"34;
%"TTL2G14"
"1","(-3675,2775)","0","mstr_ttl","I15";
;
CDS_SEC"2"
CDS_LIB"mstr_ttl"
PACK_TYPE"SMLF"
SEC_TYPE"SMLF"
SEC"2"
CDS_LOCATION"U9A3"
ROOM"MIO_CHASSIS"
BOM_COST"MIO_CHASSIS"
MATERIAL"IC"
LOCATION"U9A3"
VALUE"74LVC2G14"
PART_NUMBER"D18476-001"
POWER_GROUP"VCC=P3V3_STBY;GND=GND";
"A <SIZE-1..0>"
$PN"3"28;
"Y <SIZE -1..0> \B"
$PN"4"19;
%"TTL2G14"
"1","(-4625,2775)","0","mstr_ttl","I18";
;
CDS_SEC"1"
ROOM"MIO_CHASSIS"
CDS_LOCATION"U9A3"
SEC"1"
CDS_LIB"mstr_ttl"
SEC_TYPE"SMLF"
PACK_TYPE"SMLF"
BOM_COST"MIO_CHASSIS"
MATERIAL"IC"
VALUE"74LVC2G14"
PART_NUMBER"D18476-001"
LOCATION"U9A3"
POWER_GROUP"VCC=P3V3_STBY;GND=GND";
"A <SIZE-1..0>"
$PN"1"29;
"Y <SIZE -1..0> \B"
$PN"6"28;
%"CAP_A"
"1","(-4925,2550)","0","dev_discrete","I19";
;
CDS_LIB"dev_discrete"
CDS_LOCATION"C1L10"
SEC_TYPE"0402V"
CDS_SEC"1"
BOM_COST"MIO_CHASSIS"
ROOM"MIO_CHASSIS"
SEC"1"
PACK_TYPE"0402V"
MATERIAL"X6S"
TOLERANCE"10%"
VOLTAGE"6.3V"
VALUE"1.0UF"
LOCATION"C1L10"
PART_NUMBER"D97712-004";
"B"
$PN"2"2;
"A"
$PN"1"29;
%"GND"
"1","(-4925,2275)","0","mstr_symbols","I20";
;
VOLTAGE"0.0V"
CDS_LIB"mstr_symbols"
SIZE"1B"
BODY_TYPE"PLUMBING"
HDL_POWER"GND";
"A\NAC"2;
%"P3V3_STBY"
"1","(-5875,3400)","0","mstr_symbols","I21";
;
VOLTAGE"3.3V"
SIZE"1B"
CDS_LIB"mstr_symbols"
BODY_TYPE"PLUMBING"
HDL_POWER"P3V3_STBY";
"G\NAC"3;
%"RES"
"1","(-5600,2775)","0","mstr_discrete","I22";
;
CDS_SEC"1"
ROOM"MIO_CHASSIS"
CDS_LOCATION"R1L22"
SEC"1"
SEC_TYPE"0402"
BOM_COST"MIO_CHASSIS"
CDS_LIB"mstr_discrete"
VALUE"200.0"
MATERIAL"CHIP"
WATTAGE"1/16W"
PART_NUMBER"G21796-004"
LOCATION"R1L22"
PACK_TYPE"0402"
TOLERANCE"1%";
"B"
$PN"2"29;
"A"
$PN"1"23;
%"RES"
"2","(-5875,3075)","0","mstr_discrete","I24";
;
CDS_SEC"1"
CDS_LIB"mstr_discrete"
CDS_LOCATION"R1L19"
ROOM"MIO_CHASSIS"
SEC"1"
SEC_TYPE"0402"
BOM_COST"MIO_CHASSIS"
PACK_TYPE"0402"
MATERIAL"EMPTY"
PART_NUMBER"G21796-072"
WATTAGE"1/16W"
TOLERANCE"1%"
VALUE"4.75K"
LOCATION"R1L19";
"A"
$PN"1"3;
"B"
$PN"2"23;
%"GND"
"1","(-7625,2250)","0","mstr_symbols","I27";
;
VOLTAGE"0.0V"
SIZE"1B"
CDS_LIB"mstr_symbols"
BODY_TYPE"PLUMBING"
HDL_POWER"GND";
"A\NAC"4;
%"GND"
"1","(-7675,3650)","0","mstr_symbols","I3";
;
VOLTAGE"0.0V"
SIZE"1B"
CDS_LIB"mstr_symbols"
BODY_TYPE"PLUMBING"
HDL_POWER"GND";
"A\NAC"5;
%"RES"
"1","(-2225,2775)","0","mstr_discrete","I35";
;
CDS_SEC"1"
CDS_LIB"mstr_discrete"
SEC_TYPE"0402"
BOM_COST"MIO_CHASSIS"
SEC"1"
CDS_LOCATION"R9A9"
ROOM"MIO_CHASSIS"
PACK_TYPE"0402"
TOLERANCE"1%"
LOCATION"R9A9"
PART_NUMBER"G21796-017"
WATTAGE"1/16W"
MATERIAL"CHIP"
VALUE"100.0";
"B"
$PN"2"20;
"A"
$PN"1"19;
%"CAP_A"
"1","(-4400,4675)","0","dev_discrete","I37";
;
CDS_LIB"dev_discrete"
SEC"1"
SEC_TYPE"0402V"
CDS_SEC"1"
BOM_COST"MIO_CHASSIS"
CDS_LOCATION"C1L17"
ROOM"MIO_CHASSIS"
MATERIAL"X7R"
PACK_TYPE"0402V"
VOLTAGE"16V"
TOLERANCE"10%"
VALUE"0.1UF"
LOCATION"C1L17"
PART_NUMBER"A36096-030";
"B"
$PN"2"7;
"A"
$PN"1"8;
%"CAP_A"
"1","(-4500,3350)","0","dev_discrete","I38";
;
SEC"1"
CDS_SEC"1"
CDS_LIB"dev_discrete"
CDS_LOCATION"C1L9"
ROOM"MIO_CHASSIS"
SEC_TYPE"0402V"
BOM_COST"MIO_CHASSIS"
PART_NUMBER"A36096-030"
PACK_TYPE"0402V"
TOLERANCE"10%"
MATERIAL"X7R"
VOLTAGE"16V"
LOCATION"C1L9"
VALUE"0.1UF";
"B"
$PN"2"6;
"A"
$PN"1"9;
%"RES"
"1","(-5650,4175)","0","mstr_discrete","I4";
;
CDS_SEC"1"
CDS_LIB"mstr_discrete"
CDS_LOCATION"R1L31"
ROOM"MIO_CHASSIS"
SEC_TYPE"0402"
BOM_COST"MIO_CHASSIS"
SEC"1"
PACK_TYPE"0402"
WATTAGE"1/16W"
MATERIAL"CHIP"
TOLERANCE"1%"
VALUE"200.0"
PART_NUMBER"G21796-004"
LOCATION"R1L31";
"B"
$PN"2"30;
"A"
$PN"1"22;
%"CAP_A"
"1","(-575,3500)","0","dev_discrete","I40";
;
CDS_LIB"dev_discrete"
CDS_SEC"1"
CDS_LOCATION"C9A3"
ROOM"MIO_CHASSIS"
BOM_COST"MIO_CHASSIS"
SEC_TYPE"0402V"
SEC"1"
MATERIAL"X7R"
VOLTAGE"16V"
PACK_TYPE"0402V"
TOLERANCE"10%"
VALUE"0.1UF"
PART_NUMBER"A36096-030"
LOCATION"C9A3";
"B"
$PN"2"15;
"A"
$PN"1"14;
%"GND"
"1","(-4500,3050)","0","mstr_symbols","I41";
;
SIZE"1B"
VOLTAGE"0.0V"
CDS_LIB"mstr_symbols"
BODY_TYPE"PLUMBING"
HDL_POWER"GND";
"A\NAC"6;
%"GND"
"1","(-4400,4425)","0","mstr_symbols","I42";
;
CDS_LIB"mstr_symbols"
VOLTAGE"0.0V"
SIZE"1B"
BODY_TYPE"PLUMBING"
HDL_POWER"GND";
"A\NAC"7;
%"P3V3_STBY"
"1","(-4400,4900)","0","mstr_symbols","I43";
;
VOLTAGE"3.3V"
CDS_LIB"mstr_symbols"
SIZE"1B"
BODY_TYPE"PLUMBING"
HDL_POWER"P3V3_STBY";
"G\NAC"8;
%"P3V3_STBY"
"1","(-4500,3650)","0","mstr_symbols","I44";
;
SIZE"1B"
VOLTAGE"3.3V"
CDS_LIB"mstr_symbols"
BODY_TYPE"PLUMBING"
HDL_POWER"P3V3_STBY";
"G\NAC"9;
%"RES"
"1","(-4000,1550)","0","mstr_discrete","I45";
;
CDS_SEC"1"
CDS_LOCATION"R1L33"
SEC"1"
ROOM"MIO_CHASSIS"
CDS_LIB"mstr_discrete"
BOM_COST"MIO_CHASSIS"
SEC_TYPE"0402"
MATERIAL"CHIP"
PART_NUMBER"G21796-271"
LOCATION"R1L33"
WATTAGE"1/16W"
VALUE"221"
TOLERANCE"1.0%"
PACK_TYPE"0402";
"B"
$PN"2"16;
"A"
$PN"1"18;
%"FET_N"
"8","(-5025,1175)","0","mstr_discrete","I49";
;
CDS_SEC"1"
CDS_LIB"mstr_discrete"
ROOM"MIO_CHASSIS"
CDS_LOCATION"Q9A3"
SEC"1"
BOM_COST"MIO_CHASSIS"
SEC_TYPE"SOT23LF"
PACK_TYPE"SOT23LF"
PART_NUMBER"C79254-001"
VALUE"2N7002"
MATERIAL"FET"
LOCATION"Q9A3";
"GATE"
$PN"1"25;
"DRN"
$PN"3"36;
"SRC"
$PN"2"10;
%"RES"
"2","(-5925,4475)","0","mstr_discrete","I5";
;
CDS_SEC"1"
CDS_LIB"mstr_discrete"
CDS_LOCATION"R1L27"
BOM_COST"MIO_CHASSIS"
SEC_TYPE"0402"
SEC"1"
ROOM"MIO_CHASSIS"
PACK_TYPE"0402"
LOCATION"R1L27"
VALUE"4.75K"
TOLERANCE"1%"
MATERIAL"CHIP"
WATTAGE"1/16W"
PART_NUMBER"G21796-072";
"A"
$PN"1"12;
"B"
$PN"2"22;
%"LED"
"3","(-1700,1025)","0","mstr_discrete","I50";
;
ROOM"MIO_CHASSIS"
CDS_LOCATION"DS9A1"
$SEC"1"
CDS_SEC"1"
BOM_COST"MIO_CHASSIS"
PACK_TYPE"1NC"
CDS_LIB"mstr_discrete"
COLOR"BLUE"
MATERIAL"IC"
LOCATION"DS9A1"
PART_NUMBER"C96565-012";
"A"
$PN"2"21;
"C"
$PN"1"33;
%"GND"
"1","(-5025,750)","0","mstr_symbols","I54";
;
VOLTAGE"0.0V"
SIZE"1B"
CDS_LIB"mstr_symbols"
BODY_TYPE"PLUMBING"
HDL_POWER"GND";
"A\NAC"10;
%"TTL1G86"
"1","(-2750,1025)","0","mstr_ttl","I57";
;
CDS_LOCATION"U1L2"
PACK_TYPE"SOTLF"
BOM_COST"MIO_CHASSIS"
CDS_SEC"1"
$SEC"1"
ROOM"MIO_CHASSIS"
CDS_LIB"mstr_ttl"
PART_NUMBER"D39848-001"
POWER_GROUP"VCC=P5V_STBY;GND=GND;"
MATERIAL"IC"
LOCATION"U1L2"
VALUE"74AHCT1G86";
"Y"
$PN"4"33;
"A"
$PN"1"32;
"B"
$PN"2"24;
%"RES"
"2","(-1175,1350)","0","mstr_discrete","I58";
;
CDS_SEC"1"
CDS_LOCATION"R1L8"
CDS_LIB"mstr_discrete"
ROOM"MIO_CHASSIS"
SEC"1"
BOM_COST"MIO_CHASSIS"
SEC_TYPE"0402"
LOCATION"R1L8"
PACK_TYPE"0402"
VALUE"470.0"
TOLERANCE"5%"
WATTAGE"1/16W"
MATERIAL"CHIP"
PART_NUMBER"G21497-024";
"A"
$PN"1"11;
"B"
$PN"2"21;
%"P5V_STBY"
"1","(-1175,1700)","0","mstr_symbols","I59";
;
SIZE"1B"
CDS_LIB"mstr_symbols"
VOLTAGE"5.0V"
BODY_TYPE"PLUMBING"
HDL_POWER"P5V_STBY";
"G\NAC"11;
%"P3V3_STBY"
"1","(-5925,4800)","0","mstr_symbols","I6";
;
VOLTAGE"3.3V"
CDS_LIB"mstr_symbols"
SIZE"1B"
BODY_TYPE"PLUMBING"
HDL_POWER"P3V3_STBY";
"G\NAC"12;
%"RES"
"1","(-3525,1075)","0","mstr_discrete","I63";
;
CDS_SEC"1"
CDS_LOCATION"R1L12"
CDS_LIB"mstr_discrete"
SEC_TYPE"0402"
SEC"1"
ROOM"MIO_CHASSIS"
BOM_COST"MIO_CHASSIS"
PACK_TYPE"0402"
MATERIAL"CHIP"
TOLERANCE"5%"
LOCATION"R1L12"
PART_NUMBER"G21497-005"
VALUE"0.0"
WATTAGE"1/16W";
"B"
$PN"2"32;
"A"
$PN"1"27;
%"CAP_A"
"1","(-2900,1725)","0","dev_discrete","I64";
;
CDS_LIB"dev_discrete"
CDS_SEC"1"
ROOM"MIO_CHASSIS"
SEC"1"
CDS_LOCATION"C1L4"
BOM_COST"MIO_CHASSIS"
SEC_TYPE"0402V"
LOCATION"C1L4"
VOLTAGE"16V"
PACK_TYPE"0402V"
MATERIAL"X7R"
VALUE"0.1UF"
PART_NUMBER"A36096-030"
TOLERANCE"10%";
"B"
$PN"2"13;
"A"
$PN"1"17;
%"GND"
"1","(-2900,1475)","0","mstr_symbols","I66";
;
VOLTAGE"0.0V"
CDS_LIB"mstr_symbols"
SIZE"1B"
BODY_TYPE"PLUMBING"
HDL_POWER"GND";
"A\NAC"13;
%"LED"
"3","(-4600,1550)","0","mstr_discrete","I67";
;
CDS_SEC"1"
ROOM"MIO_CHASSIS"
CDS_LOCATION"DS9A3"
SEC"1"
BOM_COST"MIO_CHASSIS"
SEC_TYPE"1NCLF"
PACK_TYPE"1NCLF"
CDS_LIB"mstr_discrete"
MATERIAL"IC"
LOCATION"DS9A3"
COLOR"YELLOW"
PART_NUMBER"C96565-003";
"A"
$PN"2"18;
"C"
$PN"1"36;
%"P3V3_STBY"
"1","(-575,3800)","0","mstr_symbols","I70";
;
SIZE"1B"
VOLTAGE"3.3V"
CDS_LIB"mstr_symbols"
BODY_TYPE"PLUMBING"
HDL_POWER"P3V3_STBY";
"G\NAC"14;
%"GND"
"1","(-575,3200)","0","mstr_symbols","I71";
;
CDS_LIB"mstr_symbols"
VOLTAGE"0.0V"
SIZE"1B"
BODY_TYPE"PLUMBING"
HDL_POWER"GND";
"A\NAC"15;
%"SWITCH_D37771002"
"1","(-7075,2675)","3","mstr_misc","I78";
;
CDS_SEC"1"
SEC"1"
SEC_TYPE"SM"
PACK_TYPE"SM"
CDS_LOCATION"S9A1"
CDS_LIB"mstr_misc"
CDS_LMAN_SYM_OUTLINE"-100,125,100,-75"
ROOM"MIO_CHASSIS"
BOM_COST"MIO_CHASSIS"
PART_NUMBER"D37771-002"
LOCATION"S9A1"
MATERIAL"IC";
"PIN4"
$PN"4"4;
"PIN2"
$PN"2"23;
"PIN1"
$PN"1"23;
"PIN3"
$PN"3"4;
%"SW_H67881001"
"1","(-7150,4075)","0","mstr_misc","I84";
;
CDS_LMAN_SYM_OUTLINE"-200,200,200,-200"
CDS_LIB"mstr_misc"
ROOM"MIO_CHASSIS"
CDS_LOCATION"S9A2"
$SEC"1"
CDS_SEC"1"
PACK_TYPE"SM"
BOM_COST"MIO_CHASSIS"
LOCATION"S9A2"
PART_NUMBER"H67881-001"
MATERIAL"IC";
"IO2"
$PN"2"22;
"IO1"
$PN"1"22;
"IO3"
$PN"3"5;
"IO4"
$PN"4"5;
%"P3V3_STBY"
"1","(-3700,1825)","0","mstr_symbols","I85";
;
VOLTAGE"3.3V"
CDS_LIB"mstr_symbols"
SIZE"1B"
BODY_TYPE"PLUMBING"
HDL_POWER"P3V3_STBY";
"G\NAC"16;
%"P5V_STBY"
"1","(-2900,1975)","0","mstr_symbols","I86";
;
VOLTAGE"5.0V"
CDS_LIB"mstr_symbols"
SIZE"1B"
BODY_TYPE"PLUMBING"
HDL_POWER"P5V_STBY";
"G\NAC"17;
%"0R2J-L-GP"
"1","(-5550,1550)","1","w_hdl","I89";
;
CDS_SEC"1"
$SEC"1"
CDS_LOCATION"R1L45"
PACK_TYPE"SMD-RG5"
PART_NUMBER"63.R0034.L0L"
CDS_LIB"w_hdl"
CDS_LMAN_SYM_OUTLINE"-50,75,50,-75"
LOCATION"R1L45"
VALUE"0R2J-L-GP";
"2"
$PN"2"36;
"1"
$PN"1"26;
%"TTL2G14"
"1","(-4675,4175)","0","mstr_ttl","I9";
;
CDS_SEC"1"
CDS_LIB"mstr_ttl"
SEC_TYPE"SMLF"
BOM_COST"MIO_CHASSIS"
SEC"1"
PACK_TYPE"SMLF"
CDS_LOCATION"U9A4"
ROOM"MIO_CHASSIS"
PART_NUMBER"D18476-001"
MATERIAL"IC"
LOCATION"U9A4"
VALUE"74LVC2G14"
POWER_GROUP"VCC=P3V3_STBY;GND=GND";
"A <SIZE-1..0>"
$PN"1"30;
"Y <SIZE -1..0> \B"
$PN"6"31;
END.
